# T6G (Grand Teton) — schematic netlist excerpt (pin names and nets, part order shuffled) for the footprints in the layout excerpt that follows; sources: Cadence DE-HDL packaged netlist, KiCad conversion of 04192023_DAF0TMB3IC0_F0TG_MB_C_brd_V02_OCP.brd

J75  PICOPROBE_BXA  DELTA-L 4.0 EMPTY  pkg TRIANG_LAUNCH_3PXB  page 229
  \1_p\  = DELTA_L_85_10INCH_TOP_DP
  \2_n\  = DELTA_L_85_10INCH_TOP_DN
  \3_g\  = DELTA_L_GND_1

R6715  Q_RES  20K 1% CHIP  pkg 0201LF  page 320 : A = RT_CPU1_P0_ADDR2 ; B = GND

(kicad_pcb
	(version 20260206)
	(generator "pcbnew")
	(generator_version "10.0")
	(general
		(thickness 1.6)
		(legacy_teardrops no)
	)
	(paper "A4")
	(title_block
		(title "04192023_DAF0TMB3IC0_F0TG_MB_C_brd_V02_OCP.brd")
		(comment 1 "Grand Teton / footprints 3409-3410 of 8354")
	)
	(layers
		(0 "F.Cu" signal "TOP")
		(4 "In1.Cu" signal "GND")
		(6 "In2.Cu" signal "IN1")
		(8 "In3.Cu" signal "GND1")
		(10 "In4.Cu" signal "IN2")
		(12 "In5.Cu" signal "GND2")
		(14 "In6.Cu" signal "IN3")
		(16 "In7.Cu" signal "GND3")
		(18 "In8.Cu" signal "VCC")
		(20 "In9.Cu" signal "VCC1")
		(22 "In10.Cu" signal "GND4")
		(24 "In11.Cu" signal "IN4")
		(26 "In12.Cu" signal "GND5")
		(28 "In13.Cu" signal "IN5")
		(30 "In14.Cu" signal "GND6")
		(32 "In15.Cu" signal "IN6")
		(34 "In16.Cu" signal "GND7")
		(2 "B.Cu" signal "BOTTOM")
		(9 "F.Adhes" user "F.Adhesive")
		(11 "B.Adhes" user "B.Adhesive")
		(13 "F.Paste" user "Package Geometry/Pastemask Top")
		(15 "B.Paste" user "Package Geometry/Pastemask Bottom")
		(5 "F.SilkS" user "Ref Des/Silkscreen Top")
		(7 "B.SilkS" user "Ref Des/Silkscreen Bottom")
		(1 "F.Mask" user "Board Geometry/Soldermask Top")
		(3 "B.Mask" user "Board Geometry/Soldermask Bottom")
		(17 "Dwgs.User" user "User.Drawings")
		(19 "Cmts.User" user "User.Comments")
		(21 "Eco1.User" user "User.Eco1")
		(23 "Eco2.User" user "User.Eco2")
		(25 "Edge.Cuts" user "Board Geometry/Outline")
		(27 "Margin" user)
		(31 "F.CrtYd" user "Package Geometry/Place Bound Top")
		(29 "B.CrtYd" user "Package Geometry/Place Bound Bottom")
		(35 "F.Fab" user "Ref Des/Assembly Top")
		(33 "B.Fab" user "Ref Des/Assembly Bottom")
	)
	(footprint ""
		(layer "F.Cu")
		(at 212.471508 0.002794)
		(property "Reference" "J75"
			(at -4.427728 1.119632 90)
			(unlocked yes)
			(layer "F.SilkS")
			(effects
				(font
					(size 0.7874 0.5842)
					(thickness 0.1524)
				)
				(justify left)
			)
		)
		(property "Value" ""
			(at 0 0 0)
			(layer "F.Fab")
			(effects
				(font
					(size 1.27 1.27)
				)
			)
		)
		(duplicate_pad_numbers_are_jumpers no)
		(fp_line
			(start -1.2192 -2.06756)
			(end 1.2192 -2.06756)
			(stroke
				(width 0.1524)
				(type default)
			)
			(layer "F.SilkS")
		)
		(fp_line
			(start -1.2192 2.06756)
			(end -1.2192 -2.06756)
			(stroke
				(width 0.1524)
				(type default)
			)
			(layer "F.SilkS")
		)
		(fp_line
			(start 1.2192 -2.06756)
			(end 1.2192 2.06756)
			(stroke
				(width 0.1524)
				(type default)
			)
			(layer "F.SilkS")
		)
		(fp_line
			(start 1.2192 2.06756)
			(end -1.2192 2.06756)
			(stroke
				(width 0.1524)
				(type default)
			)
			(layer "F.SilkS")
		)
		(pad "" np_thru_hole circle
			(at -2.8829 -1.27 270)
			(size 1.0414 1.0414)
			(drill 1.0414)
			(layers "*.Cu" "*.Mask")
			(clearance 0.381)
			(thermal_gap 0.381)
		)
		(pad "" np_thru_hole circle
			(at -2.8829 1.27 270)
			(size 1.0414 1.0414)
			(drill 1.0414)
			(layers "*.Cu" "*.Mask")
			(clearance 0.381)
			(thermal_gap 0.381)
		)
		(pad "" np_thru_hole circle
			(at 3.4671 -1.27 270)
			(size 1.0414 1.0414)
			(drill 1.0414)
			(layers "*.Cu" "*.Mask")
			(clearance 0.381)
			(thermal_gap 0.381)
		)
		(pad "" np_thru_hole circle
			(at 3.4671 1.27 270)
			(size 1.0414 1.0414)
			(drill 1.0414)
			(layers "*.Cu" "*.Mask")
			(clearance 0.381)
			(thermal_gap 0.381)
		)
		(pad "1" smd rect
			(at 0.8255 -0.249936 270)
			(size 0.3048 0.508)
			(layers "F.Cu" "F.Mask" "F.Paste")
			(net "DELTA_L_85_10INCH_TOP_DP")
		)
		(pad "2" smd rect
			(at 0.8255 0.249936 270)
			(size 0.3048 0.508)
			(layers "F.Cu" "F.Mask" "F.Paste")
			(net "DELTA_L_85_10INCH_TOP_DN")
		)
		(pad "3" smd circle
			(at 0 0)
			(size 0 0)
			(layers "F.Cu" "F.Mask" "F.Paste")
			(net "DELTA_L_GND_1")
		)
		(zone
			(layer "F.Cu")
			(hatch none 0.5)
			(connect_pads
				(clearance 0)
			)
			(min_thickness 0.25)
			(keepout
				(tracks not_allowed)
				(vias allowed)
				(pads allowed)
				(copperpour not_allowed)
				(footprints allowed)
			)
			(placement
				(enabled no)
				(sheetname "")
			)
			(fill
				(thermal_gap 0.5)
				(thermal_bridge_width 0.5)
				(island_removal_mode 0)
			)
			(polygon
				(pts
					(xy 213.589108 -0.545846) (xy 213.589108 -0.450342) (xy 212.992208 -0.450342) (xy 212.992208 -0.043942)
					(xy 213.589108 -0.043942) (xy 213.589108 0.04953) (xy 212.992208 0.04953) (xy 212.992208 0.45593)
					(xy 213.589108 0.45593) (xy 213.589108 0.551434) (xy 212.890608 0.551434) (xy 212.890608 -0.545846)
				)
			)
		)
		(zone
			(layers "F.Cu" "B.Cu" "In1.Cu" "In2.Cu" "In3.Cu" "In4.Cu" "In5.Cu" "In6.Cu"
				"In7.Cu" "In8.Cu" "In9.Cu" "In10.Cu" "In11.Cu" "In12.Cu" "In13.Cu" "In14.Cu"
				"In15.Cu" "In16.Cu"
			)
			(hatch none 0.5)
			(connect_pads
				(clearance 0)
			)
			(min_thickness 0.25)
			(keepout
				(tracks not_allowed)
				(vias allowed)
				(pads allowed)
				(copperpour not_allowed)
				(footprints allowed)
			)
			(placement
				(enabled no)
				(sheetname "")
			)
			(fill
				(thermal_gap 0.5)
				(thermal_bridge_width 0.5)
				(island_removal_mode 0)
			)
			(polygon
				(pts
					(arc
						(start 210.515708 -1.267206)
						(mid 208.661508 -1.267206)
						(end 210.515708 -1.267206)
					)
				)
			)
		)
		(zone
			(layers "F.Cu" "B.Cu" "In1.Cu" "In2.Cu" "In3.Cu" "In4.Cu" "In5.Cu" "In6.Cu"
				"In7.Cu" "In8.Cu" "In9.Cu" "In10.Cu" "In11.Cu" "In12.Cu" "In13.Cu" "In14.Cu"
				"In15.Cu" "In16.Cu"
			)
			(hatch none 0.5)
			(connect_pads
				(clearance 0)
			)
			(min_thickness 0.25)
			(keepout
				(tracks not_allowed)
				(vias allowed)
				(pads allowed)
				(copperpour not_allowed)
				(footprints allowed)
			)
			(placement
				(enabled no)
				(sheetname "")
			)
			(fill
				(thermal_gap 0.5)
				(thermal_bridge_width 0.5)
				(island_removal_mode 0)
			)
			(polygon
				(pts
					(arc
						(start 210.515708 1.272794)
						(mid 208.661508 1.272794)
						(end 210.515708 1.272794)
					)
				)
			)
		)
		(zone
			(layers "F.Cu" "B.Cu" "In1.Cu" "In2.Cu" "In3.Cu" "In4.Cu" "In5.Cu" "In6.Cu"
				"In7.Cu" "In8.Cu" "In9.Cu" "In10.Cu" "In11.Cu" "In12.Cu" "In13.Cu" "In14.Cu"
				"In15.Cu" "In16.Cu"
			)
			(hatch none 0.5)
			(connect_pads
				(clearance 0)
			)
			(min_thickness 0.25)
			(keepout
				(tracks not_allowed)
				(vias allowed)
				(pads allowed)
				(copperpour not_allowed)
				(footprints allowed)
			)
			(placement
				(enabled no)
				(sheetname "")
			)
			(fill
				(thermal_gap 0.5)
				(thermal_bridge_width 0.5)
				(island_removal_mode 0)
			)
			(polygon
				(pts
					(arc
						(start 216.865708 -1.267206)
						(mid 215.011508 -1.267206)
						(end 216.865708 -1.267206)
					)
				)
			)
		)
		(zone
			(layers "F.Cu" "B.Cu" "In1.Cu" "In2.Cu" "In3.Cu" "In4.Cu" "In5.Cu" "In6.Cu"
				"In7.Cu" "In8.Cu" "In9.Cu" "In10.Cu" "In11.Cu" "In12.Cu" "In13.Cu" "In14.Cu"
				"In15.Cu" "In16.Cu"
			)
			(hatch none 0.5)
			(connect_pads
				(clearance 0)
			)
			(min_thickness 0.25)
			(keepout
				(tracks not_allowed)
				(vias allowed)
				(pads allowed)
				(copperpour not_allowed)
				(footprints allowed)
			)
			(placement
				(enabled no)
				(sheetname "")
			)
			(fill
				(thermal_gap 0.5)
				(thermal_bridge_width 0.5)
				(island_removal_mode 0)
			)
			(polygon
				(pts
					(arc
						(start 216.865708 1.272794)
						(mid 215.011508 1.272794)
						(end 216.865708 1.272794)
					)
				)
			)
		)
	)
	(footprint ""
		(layer "F.Cu")
		(at 72.6948 -386.7912 90)
		(property "Reference" "R6715"
			(at 0 0 90)
			(layer "F.SilkS")
			(hide yes)
			(effects
				(font
					(size 1.27 1.27)
				)
			)
		)
		(property "Value" ""
			(at 0 0 90)
			(layer "F.Fab")
			(effects
				(font
					(size 1.27 1.27)
				)
			)
		)
		(duplicate_pad_numbers_are_jumpers no)
		(fp_line
			(start 0.32512 -0.175006)
			(end 0.32512 0.175006)
			(stroke
				(width 0.1)
				(type default)
			)
			(layer "F.Fab")
		)
		(fp_line
			(start -0.32512 -0.175006)
			(end 0.32512 -0.175006)
			(stroke
				(width 0.1)
				(type default)
			)
			(layer "F.Fab")
		)
		(fp_line
			(start 0.32512 0.175006)
			(end -0.32512 0.175006)
			(stroke
				(width 0.1)
				(type default)
			)
			(layer "F.Fab")
		)
		(fp_line
			(start -0.32512 0.175006)
			(end -0.32512 -0.175006)
			(stroke
				(width 0.1)
				(type default)
			)
			(layer "F.Fab")
		)
		(pad "1" smd rect
			(at -0.2667 0 90)
			(size 0.3048 0.381)
			(layers "F.Cu" "F.Mask" "F.Paste")
			(net "RT_CPU1_P0_ADDR2")
		)
		(pad "2" smd rect
			(at 0.2667 0 270)
			(size 0.3048 0.381)
			(layers "F.Cu" "F.Mask" "F.Paste")
			(net "GND")
		)
	)
)
